# T6G (Grand Teton) — schematic netlist excerpt (pin names and nets, part order shuffled) for the footprints in the layout excerpt that follows; sources: Cadence DE-HDL packaged netlist, KiCad conversion of 04192023_DAF0TMB3IC0_F0TG_MB_C_brd_V02_OCP.brd

PC2348  Q_CAP  1NF 50V 10% EMPTY  pkg 0402  page 263 : A = HSC_OCREF ; B = AGND_HSC
PC6011  Q_CAP  1UF 25V 10% X6S  pkg C0402  page 270 : A = SW_P12V_AUX_P1V2_AUX_FLT ; B = GND

(kicad_pcb
	(version 20260206)
	(generator "pcbnew")
	(generator_version "10.0")
	(general
		(thickness 1.6)
		(legacy_teardrops no)
	)
	(paper "A4")
	(title_block
		(title "04192023_DAF0TMB3IC0_F0TG_MB_C_brd_V02_OCP.brd")
		(comment 1 "Grand Teton / footprints 4145-4146 of 8354")
	)
	(layers
		(0 "F.Cu" signal "TOP")
		(4 "In1.Cu" signal "GND")
		(6 "In2.Cu" signal "IN1")
		(8 "In3.Cu" signal "GND1")
		(10 "In4.Cu" signal "IN2")
		(12 "In5.Cu" signal "GND2")
		(14 "In6.Cu" signal "IN3")
		(16 "In7.Cu" signal "GND3")
		(18 "In8.Cu" signal "VCC")
		(20 "In9.Cu" signal "VCC1")
		(22 "In10.Cu" signal "GND4")
		(24 "In11.Cu" signal "IN4")
		(26 "In12.Cu" signal "GND5")
		(28 "In13.Cu" signal "IN5")
		(30 "In14.Cu" signal "GND6")
		(32 "In15.Cu" signal "IN6")
		(34 "In16.Cu" signal "GND7")
		(2 "B.Cu" signal "BOTTOM")
		(9 "F.Adhes" user "F.Adhesive")
		(11 "B.Adhes" user "B.Adhesive")
		(13 "F.Paste" user "Package Geometry/Pastemask Top")
		(15 "B.Paste" user "Package Geometry/Pastemask Bottom")
		(5 "F.SilkS" user "Ref Des/Silkscreen Top")
		(7 "B.SilkS" user "Ref Des/Silkscreen Bottom")
		(1 "F.Mask" user "Board Geometry/Soldermask Top")
		(3 "B.Mask" user "Board Geometry/Soldermask Bottom")
		(17 "Dwgs.User" user "User.Drawings")
		(19 "Cmts.User" user "User.Comments")
		(21 "Eco1.User" user "User.Eco1")
		(23 "Eco2.User" user "User.Eco2")
		(25 "Edge.Cuts" user "Board Geometry/Outline")
		(27 "Margin" user)
		(31 "F.CrtYd" user "Package Geometry/Place Bound Top")
		(29 "B.CrtYd" user "Package Geometry/Place Bound Bottom")
		(35 "F.Fab" user "Ref Des/Assembly Top")
		(33 "B.Fab" user "Ref Des/Assembly Bottom")
	)
	(footprint ""
		(layer "F.Cu")
		(at 119.135652 -76.743052 90)
		(property "Reference" "PC6011"
			(at 0 0 90)
			(layer "F.SilkS")
			(hide yes)
			(effects
				(font
					(size 1.27 1.27)
				)
			)
		)
		(property "Value" ""
			(at 0 0 90)
			(layer "F.Fab")
			(effects
				(font
					(size 1.27 1.27)
				)
			)
		)
		(duplicate_pad_numbers_are_jumpers no)
		(fp_line
			(start 0.7874 -0.4064)
			(end 0.7874 0.4064)
			(stroke
				(width 0.1524)
				(type default)
			)
			(layer "F.SilkS")
		)
		(fp_line
			(start -0.7874 -0.4064)
			(end 0.7874 -0.4064)
			(stroke
				(width 0.1524)
				(type default)
			)
			(layer "F.SilkS")
		)
		(fp_line
			(start 0.7874 0.4064)
			(end -0.7874 0.4064)
			(stroke
				(width 0.1524)
				(type default)
			)
			(layer "F.SilkS")
		)
		(fp_line
			(start -0.7874 0.4064)
			(end -0.7874 -0.4064)
			(stroke
				(width 0.1524)
				(type default)
			)
			(layer "F.SilkS")
		)
		(fp_line
			(start -0.12065 -0.305054)
			(end -0.12065 -0.2794)
			(stroke
				(width 0.1)
				(type default)
			)
			(layer "F.Fab")
		)
		(fp_line
			(start -0.67945 -0.305054)
			(end -0.12065 -0.305054)
			(stroke
				(width 0.1)
				(type default)
			)
			(layer "F.Fab")
		)
		(fp_line
			(start 0.67945 -0.3048)
			(end 0.67945 0.3048)
			(stroke
				(width 0.1)
				(type default)
			)
			(layer "F.Fab")
		)
		(fp_line
			(start 0.12065 -0.3048)
			(end 0.67945 -0.3048)
			(stroke
				(width 0.1)
				(type default)
			)
			(layer "F.Fab")
		)
		(fp_line
			(start 0.12065 -0.2794)
			(end 0.12065 -0.3048)
			(stroke
				(width 0.1)
				(type default)
			)
			(layer "F.Fab")
		)
		(fp_line
			(start -0.12065 -0.2794)
			(end 0.12065 -0.2794)
			(stroke
				(width 0.1)
				(type default)
			)
			(layer "F.Fab")
		)
		(fp_line
			(start 0.120396 0.2794)
			(end -0.12065 0.2794)
			(stroke
				(width 0.1)
				(type default)
			)
			(layer "F.Fab")
		)
		(fp_line
			(start -0.12065 0.2794)
			(end -0.12065 0.3048)
			(stroke
				(width 0.1)
				(type default)
			)
			(layer "F.Fab")
		)
		(fp_line
			(start 0.67945 0.3048)
			(end 0.120396 0.3048)
			(stroke
				(width 0.1)
				(type default)
			)
			(layer "F.Fab")
		)
		(fp_line
			(start 0.120396 0.3048)
			(end 0.120396 0.2794)
			(stroke
				(width 0.1)
				(type default)
			)
			(layer "F.Fab")
		)
		(fp_line
			(start -0.12065 0.3048)
			(end -0.67945 0.3048)
			(stroke
				(width 0.1)
				(type default)
			)
			(layer "F.Fab")
		)
		(fp_line
			(start -0.67945 0.3048)
			(end -0.67945 -0.305054)
			(stroke
				(width 0.1)
				(type default)
			)
			(layer "F.Fab")
		)
		(pad "1" smd circle
			(at -0.40005 0 90)
			(size 0 0)
			(layers "F.Cu" "F.Mask" "F.Paste")
			(net "SW_P12V_AUX_P1V2_AUX_FLT")
		)
		(pad "2" smd circle
			(at 0.40005 0 90)
			(size 0 0)
			(layers "F.Cu" "F.Mask" "F.Paste")
			(net "GND")
		)
	)
	(footprint ""
		(layer "F.Cu")
		(at 204.7621 -398.940782 180)
		(property "Reference" "PC2348"
			(at 0 0 180)
			(layer "F.SilkS")
			(hide yes)
			(effects
				(font
					(size 1.27 1.27)
				)
			)
		)
		(property "Value" ""
			(at 0 0 180)
			(layer "F.Fab")
			(effects
				(font
					(size 1.27 1.27)
				)
			)
		)
		(duplicate_pad_numbers_are_jumpers no)
		(fp_line
			(start 0.7874 0.4064)
			(end -0.7874 0.4064)
			(stroke
				(width 0.1524)
				(type default)
			)
			(layer "F.SilkS")
		)
		(fp_line
			(start 0.7874 -0.4064)
			(end 0.7874 0.4064)
			(stroke
				(width 0.1524)
				(type default)
			)
			(layer "F.SilkS")
		)
		(fp_line
			(start -0.7874 0.4064)
			(end -0.7874 -0.4064)
			(stroke
				(width 0.1524)
				(type default)
			)
			(layer "F.SilkS")
		)
		(fp_line
			(start -0.7874 -0.4064)
			(end 0.7874 -0.4064)
			(stroke
				(width 0.1524)
				(type default)
			)
			(layer "F.SilkS")
		)
		(fp_line
			(start 0.67945 0.3048)
			(end 0.120396 0.3048)
			(stroke
				(width 0.1)
				(type default)
			)
			(layer "F.Fab")
		)
		(fp_line
			(start 0.67945 -0.3048)
			(end 0.67945 0.3048)
			(stroke
				(width 0.1)
				(type default)
			)
			(layer "F.Fab")
		)
		(fp_line
			(start 0.12065 -0.2794)
			(end 0.12065 -0.3048)
			(stroke
				(width 0.1)
				(type default)
			)
			(layer "F.Fab")
		)
		(fp_line
			(start 0.12065 -0.3048)
			(end 0.67945 -0.3048)
			(stroke
				(width 0.1)
				(type default)
			)
			(layer "F.Fab")
		)
		(fp_line
			(start 0.120396 0.3048)
			(end 0.120396 0.2794)
			(stroke
				(width 0.1)
				(type default)
			)
			(layer "F.Fab")
		)
		(fp_line
			(start 0.120396 0.2794)
			(end -0.12065 0.2794)
			(stroke
				(width 0.1)
				(type default)
			)
			(layer "F.Fab")
		)
		(fp_line
			(start -0.12065 0.3048)
			(end -0.67945 0.3048)
			(stroke
				(width 0.1)
				(type default)
			)
			(layer "F.Fab")
		)
		(fp_line
			(start -0.12065 0.2794)
			(end -0.12065 0.3048)
			(stroke
				(width 0.1)
				(type default)
			)
			(layer "F.Fab")
		)
		(fp_line
			(start -0.12065 -0.2794)
			(end 0.12065 -0.2794)
			(stroke
				(width 0.1)
				(type default)
			)
			(layer "F.Fab")
		)
		(fp_line
			(start -0.12065 -0.305054)
			(end -0.12065 -0.2794)
			(stroke
				(width 0.1)
				(type default)
			)
			(layer "F.Fab")
		)
		(fp_line
			(start -0.67945 0.3048)
			(end -0.67945 -0.305054)
			(stroke
				(width 0.1)
				(type default)
			)
			(layer "F.Fab")
		)
		(fp_line
			(start -0.67945 -0.305054)
			(end -0.12065 -0.305054)
			(stroke
				(width 0.1)
				(type default)
			)
			(layer "F.Fab")
		)
		(pad "1" smd circle
			(at -0.40005 0 180)
			(size 0 0)
			(layers "F.Cu" "F.Mask" "F.Paste")
			(net "HSC_OCREF")
		)
		(pad "2" smd circle
			(at 0.40005 0 180)
			(size 0 0)
			(layers "F.Cu" "F.Mask" "F.Paste")
			(net "AGND_HSC")
		)
	)
)
